# T6G (Grand Teton) — schematic netlist excerpt (pin names and nets, part order shuffled) for the footprints in the layout excerpt that follows; sources: Cadence DE-HDL packaged netlist, KiCad conversion of 04192023_DAF0TMB3IC0_F0TG_MB_C_brd_V02_OCP.brd

C1792  Q_CAP_DIFFBUS  DIFF BUS_0.22UF 6.3V 20% X6S  pkg C0201  page 65 : \1\ = P5E_CPU0_G3_TX_C_DP<14> ; \2\ = P5E_CPU0_G3_TX_DP<14>
R6856  Q_RES  33 5% CHIP  pkg 0402LF  page 151 : A = SMB_SCM_2_R6_SCL ; B = P0V9_RETIMER_CPU0_PMSCL
R1485  Q_RES  4.7K 5% EMPTY  pkg 0201LF  page 309 : A = P1V8_CPU0_RT_1D ; B = JTAG_TCK_RT_CPU0_P3

(kicad_pcb
	(version 20260206)
	(generator "pcbnew")
	(generator_version "10.0")
	(general
		(thickness 1.6)
		(legacy_teardrops no)
	)
	(paper "A4")
	(title_block
		(title "04192023_DAF0TMB3IC0_F0TG_MB_C_brd_V02_OCP.brd")
		(comment 1 "Grand Teton / footprints 709-711 of 8354")
	)
	(layers
		(0 "F.Cu" signal "TOP")
		(4 "In1.Cu" signal "GND")
		(6 "In2.Cu" signal "IN1")
		(8 "In3.Cu" signal "GND1")
		(10 "In4.Cu" signal "IN2")
		(12 "In5.Cu" signal "GND2")
		(14 "In6.Cu" signal "IN3")
		(16 "In7.Cu" signal "GND3")
		(18 "In8.Cu" signal "VCC")
		(20 "In9.Cu" signal "VCC1")
		(22 "In10.Cu" signal "GND4")
		(24 "In11.Cu" signal "IN4")
		(26 "In12.Cu" signal "GND5")
		(28 "In13.Cu" signal "IN5")
		(30 "In14.Cu" signal "GND6")
		(32 "In15.Cu" signal "IN6")
		(34 "In16.Cu" signal "GND7")
		(2 "B.Cu" signal "BOTTOM")
		(9 "F.Adhes" user "F.Adhesive")
		(11 "B.Adhes" user "B.Adhesive")
		(13 "F.Paste" user "Package Geometry/Pastemask Top")
		(15 "B.Paste" user "Package Geometry/Pastemask Bottom")
		(5 "F.SilkS" user "Ref Des/Silkscreen Top")
		(7 "B.SilkS" user "Ref Des/Silkscreen Bottom")
		(1 "F.Mask" user "Board Geometry/Soldermask Top")
		(3 "B.Mask" user "Board Geometry/Soldermask Bottom")
		(17 "Dwgs.User" user "User.Drawings")
		(19 "Cmts.User" user "User.Comments")
		(21 "Eco1.User" user "User.Eco1")
		(23 "Eco2.User" user "User.Eco2")
		(25 "Edge.Cuts" user "Board Geometry/Outline")
		(27 "Margin" user)
		(31 "F.CrtYd" user "Package Geometry/Place Bound Top")
		(29 "B.CrtYd" user "Package Geometry/Place Bound Bottom")
		(35 "F.Fab" user "Ref Des/Assembly Top")
		(33 "B.Fab" user "Ref Des/Assembly Bottom")
	)
	(footprint ""
		(layer "F.Cu")
		(at 424.5356 -421.64 90)
		(property "Reference" "R1485"
			(at 0 0 90)
			(layer "F.SilkS")
			(hide yes)
			(effects
				(font
					(size 1.27 1.27)
				)
			)
		)
		(property "Value" ""
			(at 0 0 90)
			(layer "F.Fab")
			(effects
				(font
					(size 1.27 1.27)
				)
			)
		)
		(duplicate_pad_numbers_are_jumpers no)
		(fp_line
			(start 0.32512 -0.175006)
			(end 0.32512 0.175006)
			(stroke
				(width 0.1)
				(type default)
			)
			(layer "F.Fab")
		)
		(fp_line
			(start -0.32512 -0.175006)
			(end 0.32512 -0.175006)
			(stroke
				(width 0.1)
				(type default)
			)
			(layer "F.Fab")
		)
		(fp_line
			(start 0.32512 0.175006)
			(end -0.32512 0.175006)
			(stroke
				(width 0.1)
				(type default)
			)
			(layer "F.Fab")
		)
		(fp_line
			(start -0.32512 0.175006)
			(end -0.32512 -0.175006)
			(stroke
				(width 0.1)
				(type default)
			)
			(layer "F.Fab")
		)
		(pad "1" smd rect
			(at -0.2667 0 90)
			(size 0.3048 0.381)
			(layers "F.Cu" "F.Mask" "F.Paste")
			(net "P1V8_CPU0_RT_1D")
		)
		(pad "2" smd rect
			(at 0.2667 0 270)
			(size 0.3048 0.381)
			(layers "F.Cu" "F.Mask" "F.Paste")
			(net "JTAG_TCK_RT_CPU0_P3")
		)
	)
	(footprint ""
		(layer "F.Cu")
		(at 393.715748 -17.624298 90)
		(property "Reference" "C1792"
			(at 0 0 90)
			(layer "F.SilkS")
			(hide yes)
			(effects
				(font
					(size 1.27 1.27)
				)
			)
		)
		(property "Value" ""
			(at 0 0 90)
			(layer "F.Fab")
			(effects
				(font
					(size 1.27 1.27)
				)
			)
		)
		(duplicate_pad_numbers_are_jumpers no)
		(fp_line
			(start 0.299974 -0.150114)
			(end 0.299974 0.150114)
			(stroke
				(width 0.1)
				(type default)
			)
			(layer "F.Fab")
		)
		(fp_line
			(start -0.299974 -0.150114)
			(end 0.299974 -0.150114)
			(stroke
				(width 0.1)
				(type default)
			)
			(layer "F.Fab")
		)
		(fp_line
			(start 0.299974 0.150114)
			(end -0.299974 0.150114)
			(stroke
				(width 0.1)
				(type default)
			)
			(layer "F.Fab")
		)
		(fp_line
			(start -0.299974 0.150114)
			(end -0.299974 -0.150114)
			(stroke
				(width 0.1)
				(type default)
			)
			(layer "F.Fab")
		)
		(pad "1" smd rect
			(at -0.2667 0 90)
			(size 0.3048 0.381)
			(layers "F.Cu" "F.Mask" "F.Paste")
			(net "P5E_CPU0_G3_TX_C_DP<14>")
		)
		(pad "2" smd rect
			(at 0.2667 0 90)
			(size 0.3048 0.381)
			(layers "F.Cu" "F.Mask" "F.Paste")
			(net "P5E_CPU0_G3_TX_DP<14>")
		)
	)
	(footprint ""
		(layer "F.Cu")
		(at 420.017956 -369.275106 90)
		(property "Reference" "R6856"
			(at 0 0 90)
			(layer "F.SilkS")
			(hide yes)
			(effects
				(font
					(size 1.27 1.27)
				)
			)
		)
		(property "Value" ""
			(at 0 0 90)
			(layer "F.Fab")
			(effects
				(font
					(size 1.27 1.27)
				)
			)
		)
		(duplicate_pad_numbers_are_jumpers no)
		(fp_line
			(start 0.7874 -0.4064)
			(end 0.7874 0.4064)
			(stroke
				(width 0.1524)
				(type default)
			)
			(layer "F.SilkS")
		)
		(fp_line
			(start -0.7874 -0.4064)
			(end 0.7874 -0.4064)
			(stroke
				(width 0.1524)
				(type default)
			)
			(layer "F.SilkS")
		)
		(fp_line
			(start 0.7874 0.4064)
			(end -0.7874 0.4064)
			(stroke
				(width 0.1524)
				(type default)
			)
			(layer "F.SilkS")
		)
		(fp_line
			(start -0.7874 0.4064)
			(end -0.7874 -0.4064)
			(stroke
				(width 0.1524)
				(type default)
			)
			(layer "F.SilkS")
		)
		(fp_line
			(start -0.12065 -0.305054)
			(end -0.12065 -0.2794)
			(stroke
				(width 0.1)
				(type default)
			)
			(layer "F.Fab")
		)
		(fp_line
			(start -0.67945 -0.305054)
			(end -0.12065 -0.305054)
			(stroke
				(width 0.1)
				(type default)
			)
			(layer "F.Fab")
		)
		(fp_line
			(start 0.67945 -0.3048)
			(end 0.67945 0.3048)
			(stroke
				(width 0.1)
				(type default)
			)
			(layer "F.Fab")
		)
		(fp_line
			(start 0.12065 -0.3048)
			(end 0.67945 -0.3048)
			(stroke
				(width 0.1)
				(type default)
			)
			(layer "F.Fab")
		)
		(fp_line
			(start 0.12065 -0.2794)
			(end 0.12065 -0.3048)
			(stroke
				(width 0.1)
				(type default)
			)
			(layer "F.Fab")
		)
		(fp_line
			(start -0.12065 -0.2794)
			(end 0.12065 -0.2794)
			(stroke
				(width 0.1)
				(type default)
			)
			(layer "F.Fab")
		)
		(fp_line
			(start 0.120396 0.2794)
			(end -0.12065 0.2794)
			(stroke
				(width 0.1)
				(type default)
			)
			(layer "F.Fab")
		)
		(fp_line
			(start -0.12065 0.2794)
			(end -0.12065 0.3048)
			(stroke
				(width 0.1)
				(type default)
			)
			(layer "F.Fab")
		)
		(fp_line
			(start 0.67945 0.3048)
			(end 0.120396 0.3048)
			(stroke
				(width 0.1)
				(type default)
			)
			(layer "F.Fab")
		)
		(fp_line
			(start 0.120396 0.3048)
			(end 0.120396 0.2794)
			(stroke
				(width 0.1)
				(type default)
			)
			(layer "F.Fab")
		)
		(fp_line
			(start -0.12065 0.3048)
			(end -0.67945 0.3048)
			(stroke
				(width 0.1)
				(type default)
			)
			(layer "F.Fab")
		)
		(fp_line
			(start -0.67945 0.3048)
			(end -0.67945 -0.305054)
			(stroke
				(width 0.1)
				(type default)
			)
			(layer "F.Fab")
		)
		(pad "1" smd circle
			(at -0.40005 0 90)
			(size 0 0)
			(layers "F.Cu" "F.Mask" "F.Paste")
			(net "SMB_SCM_2_R6_SCL")
		)
		(pad "2" smd circle
			(at 0.40005 0 90)
			(size 0 0)
			(layers "F.Cu" "F.Mask" "F.Paste")
			(net "P0V9_RETIMER_CPU0_PMSCL")
		)
	)
)
